(kicad_sch (version 20230121) (generator eeschema)

  (paper "A3")

  (title_block
    (title "Kria K26 Devboard")
    (date "2024-03-26")
    (rev "1.2.5")
    (comment 1 "www.antmicro.com")
    (comment 2 "Antmicro Ltd.")
  )

  (junction (at 213.36 164.465) (diameter 0) (color 0 0 0 0)
  )
  (junction (at 203.835 154.94) (diameter 0) (color 0 0 0 0)
  )
  (junction (at 200.025 164.465) (diameter 0) (color 0 0 0 0)
  )
  (junction (at 206.375 164.465) (diameter 0) (color 0 0 0 0)
  )

  (bus_entry (at 260.985 140.97) (size -2.54 2.54)
    (stroke (width 0) (type default))
  )
  (bus_entry (at 172.72 135.89) (size 2.54 2.54)
    (stroke (width 0) (type default))
  )
  (bus_entry (at 260.985 135.89) (size -2.54 2.54)
    (stroke (width 0) (type default))
  )
  (bus_entry (at 172.72 143.51) (size 2.54 2.54)
    (stroke (width 0) (type default))
  )
  (bus_entry (at 260.985 143.51) (size -2.54 2.54)
    (stroke (width 0) (type default))
  )
  (bus_entry (at 172.72 140.97) (size 2.54 2.54)
    (stroke (width 0) (type default))
  )
  (bus_entry (at 172.72 138.43) (size 2.54 2.54)
    (stroke (width 0) (type default))
  )

  (wire (pts (xy 200.025 164.465) (xy 206.375 164.465))
    (stroke (width 0) (type default))
  )
  (wire (pts (xy 215.265 146.05) (xy 258.445 146.05))
    (stroke (width 0) (type default))
  )
  (wire (pts (xy 161.29 190.5) (xy 170.18 190.5))
    (stroke (width 0) (type default))
  )
  (wire (pts (xy 161.29 187.96) (xy 170.18 187.96))
    (stroke (width 0) (type default))
  )
  (bus (pts (xy 172.72 134.62) (xy 172.72 135.89))
    (stroke (width 0) (type default))
  )

  (wire (pts (xy 203.835 151.13) (xy 205.105 151.13))
    (stroke (width 0) (type default))
  )
  (wire (pts (xy 247.65 198.12) (xy 245.11 198.12))
    (stroke (width 0) (type default))
  )
  (wire (pts (xy 201.295 148.59) (xy 201.295 149.86))
    (stroke (width 0) (type default))
  )
  (wire (pts (xy 168.91 198.12) (xy 168.91 199.39))
    (stroke (width 0) (type default))
  )
  (wire (pts (xy 220.345 164.465) (xy 213.36 164.465))
    (stroke (width 0) (type default))
  )
  (bus (pts (xy 172.72 138.43) (xy 172.72 140.97))
    (stroke (width 0) (type default))
  )
  (bus (pts (xy 260.985 135.89) (xy 260.985 140.97))
    (stroke (width 0) (type default))
  )

  (wire (pts (xy 175.26 146.05) (xy 205.105 146.05))
    (stroke (width 0) (type default))
  )
  (bus (pts (xy 172.72 140.97) (xy 172.72 143.51))
    (stroke (width 0) (type default))
  )

  (wire (pts (xy 161.29 193.04) (xy 170.18 193.04))
    (stroke (width 0) (type default))
  )
  (wire (pts (xy 194.945 164.465) (xy 200.025 164.465))
    (stroke (width 0) (type default))
  )
  (wire (pts (xy 170.18 198.12) (xy 168.91 198.12))
    (stroke (width 0) (type default))
  )
  (bus (pts (xy 260.985 134.62) (xy 260.985 135.89))
    (stroke (width 0) (type default))
  )

  (wire (pts (xy 237.49 193.04) (xy 247.65 193.04))
    (stroke (width 0) (type default))
  )
  (bus (pts (xy 260.985 140.97) (xy 260.985 143.51))
    (stroke (width 0) (type default))
  )

  (wire (pts (xy 215.265 151.13) (xy 216.535 151.13))
    (stroke (width 0) (type default))
  )
  (wire (pts (xy 215.265 138.43) (xy 258.445 138.43))
    (stroke (width 0) (type default))
  )
  (wire (pts (xy 205.105 148.59) (xy 201.295 148.59))
    (stroke (width 0) (type default))
  )
  (wire (pts (xy 215.265 148.59) (xy 219.075 148.59))
    (stroke (width 0) (type default))
  )
  (wire (pts (xy 237.49 187.96) (xy 247.65 187.96))
    (stroke (width 0) (type default))
  )
  (wire (pts (xy 175.26 140.97) (xy 205.105 140.97))
    (stroke (width 0) (type default))
  )
  (wire (pts (xy 203.835 151.13) (xy 203.835 154.94))
    (stroke (width 0) (type default))
  )
  (wire (pts (xy 219.075 148.59) (xy 219.075 149.86))
    (stroke (width 0) (type default))
  )
  (wire (pts (xy 237.49 190.5) (xy 247.65 190.5))
    (stroke (width 0) (type default))
  )
  (wire (pts (xy 175.26 138.43) (xy 205.105 138.43))
    (stroke (width 0) (type default))
  )
  (wire (pts (xy 216.535 154.94) (xy 203.835 154.94))
    (stroke (width 0) (type default))
  )
  (wire (pts (xy 220.345 168.91) (xy 220.345 164.465))
    (stroke (width 0) (type default))
  )
  (bus (pts (xy 171.45 134.62) (xy 172.72 134.62))
    (stroke (width 0) (type default))
  )

  (wire (pts (xy 175.26 143.51) (xy 205.105 143.51))
    (stroke (width 0) (type default))
  )
  (wire (pts (xy 206.375 168.91) (xy 206.375 164.465))
    (stroke (width 0) (type default))
  )
  (bus (pts (xy 263.525 134.62) (xy 260.985 134.62))
    (stroke (width 0) (type default))
  )

  (wire (pts (xy 216.535 151.13) (xy 216.535 154.94))
    (stroke (width 0) (type default))
  )
  (wire (pts (xy 245.11 198.12) (xy 245.11 199.39))
    (stroke (width 0) (type default))
  )
  (wire (pts (xy 215.265 140.97) (xy 247.015 140.97))
    (stroke (width 0) (type default))
  )
  (wire (pts (xy 213.36 164.465) (xy 206.375 164.465))
    (stroke (width 0) (type default))
  )
  (wire (pts (xy 237.49 195.58) (xy 247.65 195.58))
    (stroke (width 0) (type default))
  )
  (wire (pts (xy 213.36 164.465) (xy 213.36 168.91))
    (stroke (width 0) (type default))
  )
  (wire (pts (xy 215.265 143.51) (xy 258.445 143.51))
    (stroke (width 0) (type default))
  )
  (wire (pts (xy 200.025 164.465) (xy 200.025 166.37))
    (stroke (width 0) (type default))
  )
  (wire (pts (xy 161.29 195.58) (xy 170.18 195.58))
    (stroke (width 0) (type default))
  )
  (wire (pts (xy 198.755 154.94) (xy 203.835 154.94))
    (stroke (width 0) (type default))
  )
  (bus (pts (xy 172.72 135.89) (xy 172.72 138.43))
    (stroke (width 0) (type default))
  )

  (text "PMOD" (at 204.47 126.365 0)
    (effects (font (size 2.54 2.54) (thickness 0.508) bold) (justify left bottom))
  )

  (label "HDA16_CC" (at 244.475 140.97 180) (fields_autoplaced)
    (effects (font (size 1.27 1.27)) (justify right bottom))
  )
  (label "HDA17" (at 244.475 143.51 180) (fields_autoplaced)
    (effects (font (size 1.27 1.27)) (justify right bottom))
  )
  (label "HDA13" (at 184.15 143.51 180) (fields_autoplaced)
    (effects (font (size 1.27 1.27)) (justify right bottom))
  )
  (label "HDA12" (at 184.15 140.97 180) (fields_autoplaced)
    (effects (font (size 1.27 1.27)) (justify right bottom))
  )
  (label "HDA15" (at 244.475 138.43 180) (fields_autoplaced)
    (effects (font (size 1.27 1.27)) (justify right bottom))
  )
  (label "HDA11" (at 161.29 187.96 0) (fields_autoplaced)
    (effects (font (size 1.27 1.27)) (justify left bottom))
  )
  (label "HDA12" (at 161.29 190.5 0) (fields_autoplaced)
    (effects (font (size 1.27 1.27)) (justify left bottom))
  )
  (label "HDA14" (at 161.29 195.58 0) (fields_autoplaced)
    (effects (font (size 1.27 1.27)) (justify left bottom))
  )
  (label "HDA17" (at 237.49 193.04 0) (fields_autoplaced)
    (effects (font (size 1.27 1.27)) (justify left bottom))
  )
  (label "HDA18" (at 237.49 195.58 0) (fields_autoplaced)
    (effects (font (size 1.27 1.27)) (justify left bottom))
  )
  (label "HDA11" (at 184.15 138.43 180) (fields_autoplaced)
    (effects (font (size 1.27 1.27)) (justify right bottom))
  )
  (label "HDA13" (at 161.29 193.04 0) (fields_autoplaced)
    (effects (font (size 1.27 1.27)) (justify left bottom))
  )
  (label "HDA16_CC" (at 237.49 190.5 0) (fields_autoplaced)
    (effects (font (size 1.27 1.27)) (justify left bottom))
  )
  (label "HDA18" (at 244.475 146.05 180) (fields_autoplaced)
    (effects (font (size 1.27 1.27)) (justify right bottom))
  )
  (label "HDA14" (at 184.15 146.05 180) (fields_autoplaced)
    (effects (font (size 1.27 1.27)) (justify right bottom))
  )
  (label "HDA15" (at 237.49 187.96 0) (fields_autoplaced)
    (effects (font (size 1.27 1.27)) (justify left bottom))
  )

  (global_label "PL_3V3" (shape input) (at 198.755 154.94 180) (fields_autoplaced)
    (effects (font (size 1.27 1.27)) (justify right))
    (property "Intersheetrefs" "${INTERSHEET_REFS}" (at 98.425 57.15 0)
      (effects (font (size 1.27 1.27)) hide)
    )
  )
  (global_label "PL_3V3" (shape input) (at 194.945 164.465 180) (fields_autoplaced)
    (effects (font (size 1.27 1.27)) (justify right))
    (property "Intersheetrefs" "${INTERSHEET_REFS}" (at 94.615 66.675 0)
      (effects (font (size 1.27 1.27)) hide)
    )
  )

  (hierarchical_label "HDA[11..18]" (shape input) (at 171.45 134.62 180) (fields_autoplaced)
    (effects (font (size 1.27 1.27)) (justify right))
  )
  (hierarchical_label "HDA[11..18]" (shape input) (at 263.525 134.62 0) (fields_autoplaced)
    (effects (font (size 1.27 1.27)) (justify left))
  )
  (hierarchical_label "HDA16_CC" (shape input) (at 247.015 140.97 0) (fields_autoplaced)
    (effects (font (size 1.27 1.27)) (justify left))
  )

  (symbol (lib_id "kria-k26-devboard:PinSocket_2x6_P2.54mm_Drill1.04mm_Horizontal") (at 205.105 138.43 0) (unit 1)
    (in_bom yes) (on_board yes) (dnp no) (fields_autoplaced)
    (property "Reference" "J4" (at 210.185 132.08 0)
      (effects (font (size 1.27 1.27)))
    )
    (property "Value" "PinSocket_2x6_P2.54mm_Drill1.04mm_Horizontal" (at 210.185 134.62 0)
      (effects (font (size 1.27 1.27) (thickness 0.15)) hide)
    )
    (property "Footprint" "kria-k26-devboard-footprints:PinSocket_2x6_P2.54mm_Drill1.04mm_Horizontal" (at 224.155 143.51 0)
      (effects (font (size 1.27 1.27) (thickness 0.15)) (justify left bottom) hide)
    )
    (property "Datasheet" "https://suddendocs.samtec.com/prints/ssw-1xx-xx-xxx-x-xx-xxx-xx-mkt.pdf" (at 224.155 146.05 0)
      (effects (font (size 1.27 1.27) (thickness 0.15)) (justify left bottom) hide)
    )
    (property "Manufacturer" "Samtec" (at 224.155 148.59 0)
      (effects (font (size 1.27 1.27) (thickness 0.15)) (justify left bottom) hide)
    )
    (property "MPN" "SSW-106-02-G-D-RA" (at 210.185 134.62 0)
      (effects (font (size 1.27 1.27) (thickness 0.15)))
    )
    (property "Author" "Antmicro" (at 224.155 153.67 0)
      (effects (font (size 1.27 1.27) (thickness 0.15)) (justify left bottom) hide)
    )
    (property "License" "Apache-2.0" (at 224.155 156.21 0)
      (effects (font (size 1.27 1.27) (thickness 0.15)) (justify left bottom) hide)
    )
    (pin "1")
    (pin "10")
    (pin "11")
    (pin "12")
    (pin "2")
    (pin "3")
    (pin "4")
    (pin "5")
    (pin "6")
    (pin "7")
    (pin "8")
    (pin "9")
    (instances
      (project "kria-k26-devboard"
        (path ""
          (reference "J4") (unit 1)
        )
      )
    )
  )

  (symbol (lib_id "kria-k26-devboard:GND") (at 201.295 149.86 0) (unit 1)
    (in_bom yes) (on_board yes) (dnp no)
    (property "Reference" "#PWR065" (at 201.295 156.21 0)
      (effects (font (size 1.27 1.27)) hide)
    )
    (property "Value" "GND" (at 201.295 153.67 0)
      (effects (font (size 1.27 1.27)))
    )
    (property "Footprint" "" (at 210.185 157.48 0)
      (effects (font (size 1.27 1.27) (thickness 0.15)) (justify left bottom) hide)
    )
    (property "Datasheet" "" (at 210.185 162.56 0)
      (effects (font (size 1.27 1.27) (thickness 0.15)) (justify left bottom) hide)
    )
    (property "Author" "Antmicro" (at 210.185 157.48 0)
      (effects (font (size 1.27 1.27) (thickness 0.15)) (justify left bottom) hide)
    )
    (property "License" "Apache-2.0" (at 210.185 160.02 0)
      (effects (font (size 1.27 1.27) (thickness 0.15)) (justify left bottom) hide)
    )
    (pin "1")
    (instances
      (project "kria-k26-devboard"
        (path ""
          (reference "#PWR065") (unit 1)
        )
      )
    )
  )

  (symbol (lib_id "kria-k26-devboard:GND") (at 219.075 149.86 0) (unit 1)
    (in_bom yes) (on_board yes) (dnp no)
    (property "Reference" "#PWR067" (at 219.075 156.21 0)
      (effects (font (size 1.27 1.27)) hide)
    )
    (property "Value" "GND" (at 219.075 153.67 0)
      (effects (font (size 1.27 1.27)))
    )
    (property "Footprint" "" (at 227.965 157.48 0)
      (effects (font (size 1.27 1.27) (thickness 0.15)) (justify left bottom) hide)
    )
    (property "Datasheet" "" (at 227.965 162.56 0)
      (effects (font (size 1.27 1.27) (thickness 0.15)) (justify left bottom) hide)
    )
    (property "Author" "Antmicro" (at 227.965 157.48 0)
      (effects (font (size 1.27 1.27) (thickness 0.15)) (justify left bottom) hide)
    )
    (property "License" "Apache-2.0" (at 227.965 160.02 0)
      (effects (font (size 1.27 1.27) (thickness 0.15)) (justify left bottom) hide)
    )
    (pin "1")
    (instances
      (project "kria-k26-devboard"
        (path ""
          (reference "#PWR067") (unit 1)
        )
      )
    )
  )

  (symbol (lib_id "kria-k26-devboard:C_100n_0402") (at 213.36 168.91 270) (unit 1)
    (in_bom yes) (on_board yes) (dnp no)
    (property "Reference" "C37" (at 213.995 169.545 90)
      (effects (font (size 1.524 1.524)) (justify left))
    )
    (property "Value" "C_100n_0402" (at 203.2 189.23 0)
      (effects (font (size 1.27 1.27) (thickness 0.15)) (justify left bottom) hide)
    )
    (property "Footprint" "kria-k26-devboard-footprints:C_0402_1005Metric" (at 200.66 189.23 0)
      (effects (font (size 1.27 1.27) (thickness 0.15)) (justify left bottom) hide)
    )
    (property "Datasheet" "https://search.murata.co.jp/Ceramy/image/img/A01X/G101/ENG/GRM155R61H104KE14-01.pdf" (at 198.12 189.23 0)
      (effects (font (size 1.27 1.27) (thickness 0.15)) (justify left bottom) hide)
    )
    (property "Manufacturer" "Murata" (at 193.04 189.23 0)
      (effects (font (size 1.27 1.27) (thickness 0.15)) (justify left bottom) hide)
    )
    (property "MPN" "GRM155R61H104KE14D" (at 195.58 189.23 0)
      (effects (font (size 1.27 1.27) (thickness 0.15)) (justify left bottom) hide)
    )
    (property "Val" "100n" (at 213.995 173.355 90)
      (effects (font (size 1.27 1.27) (thickness 0.15)) (justify left))
    )
    (property "License" "Apache-2.0" (at 190.5 189.23 0)
      (effects (font (size 1.27 1.27) (thickness 0.15)) (justify left bottom) hide)
    )
    (property "Author" "Antmicro" (at 187.96 189.23 0)
      (effects (font (size 1.27 1.27) (thickness 0.15)) (justify left bottom) hide)
    )
    (property "Voltage" "50V" (at 185.42 189.23 0)
      (effects (font (size 1.27 1.27)) (justify left bottom) hide)
    )
    (property "Dielectric" "X5R" (at 182.88 189.23 0)
      (effects (font (size 1.27 1.27)) (justify left bottom) hide)
    )
    (pin "1")
    (pin "2")
    (instances
      (project "kria-k26-devboard"
        (path ""
          (reference "C37") (unit 1)
        )
      )
    )
  )

  (symbol (lib_id "kria-k26-devboard:C_100n_0402") (at 220.345 168.91 270) (unit 1)
    (in_bom yes) (on_board yes) (dnp no)
    (property "Reference" "C38" (at 220.98 169.545 90)
      (effects (font (size 1.524 1.524)) (justify left))
    )
    (property "Value" "C_100n_0402" (at 210.185 189.23 0)
      (effects (font (size 1.27 1.27) (thickness 0.15)) (justify left bottom) hide)
    )
    (property "Footprint" "kria-k26-devboard-footprints:C_0402_1005Metric" (at 207.645 189.23 0)
      (effects (font (size 1.27 1.27) (thickness 0.15)) (justify left bottom) hide)
    )
    (property "Datasheet" "https://search.murata.co.jp/Ceramy/image/img/A01X/G101/ENG/GRM155R61H104KE14-01.pdf" (at 205.105 189.23 0)
      (effects (font (size 1.27 1.27) (thickness 0.15)) (justify left bottom) hide)
    )
    (property "Manufacturer" "Murata" (at 200.025 189.23 0)
      (effects (font (size 1.27 1.27) (thickness 0.15)) (justify left bottom) hide)
    )
    (property "MPN" "GRM155R61H104KE14D" (at 202.565 189.23 0)
      (effects (font (size 1.27 1.27) (thickness 0.15)) (justify left bottom) hide)
    )
    (property "Val" "100n" (at 220.98 173.355 90)
      (effects (font (size 1.27 1.27) (thickness 0.15)) (justify left))
    )
    (property "License" "Apache-2.0" (at 197.485 189.23 0)
      (effects (font (size 1.27 1.27) (thickness 0.15)) (justify left bottom) hide)
    )
    (property "Author" "Antmicro" (at 194.945 189.23 0)
      (effects (font (size 1.27 1.27) (thickness 0.15)) (justify left bottom) hide)
    )
    (property "Voltage" "50V" (at 192.405 189.23 0)
      (effects (font (size 1.27 1.27)) (justify left bottom) hide)
    )
    (property "Dielectric" "X5R" (at 189.865 189.23 0)
      (effects (font (size 1.27 1.27)) (justify left bottom) hide)
    )
    (pin "1")
    (pin "2")
    (instances
      (project "kria-k26-devboard"
        (path ""
          (reference "C38") (unit 1)
        )
      )
    )
  )

  (symbol (lib_id "kria-k26-devboard:C_1u_0402") (at 206.375 168.91 270) (unit 1)
    (in_bom yes) (on_board yes) (dnp no)
    (property "Reference" "C36" (at 207.01 169.545 90)
      (effects (font (size 1.524 1.524)) (justify left))
    )
    (property "Value" "C_1u_0402" (at 196.215 189.23 0)
      (effects (font (size 1.27 1.27) (thickness 0.15)) (justify left bottom) hide)
    )
    (property "Footprint" "kria-k26-devboard-footprints:C_0402_1005Metric" (at 193.675 189.23 0)
      (effects (font (size 1.27 1.27) (thickness 0.15)) (justify left bottom) hide)
    )
    (property "Datasheet" " " (at 191.135 189.23 0)
      (effects (font (size 1.27 1.27) (thickness 0.15)) (justify left bottom) hide)
    )
    (property "Manufacturer" "TDK" (at 186.055 189.23 0)
      (effects (font (size 1.27 1.27) (thickness 0.15)) (justify left bottom) hide)
    )
    (property "MPN" "C1005X6S1A105K050BC" (at 188.595 189.23 0)
      (effects (font (size 1.27 1.27) (thickness 0.15)) (justify left bottom) hide)
    )
    (property "Val" "1u" (at 207.01 173.355 90)
      (effects (font (size 1.27 1.27) (thickness 0.15)) (justify left))
    )
    (property "License" "Apache-2.0" (at 183.515 189.23 0)
      (effects (font (size 1.27 1.27) (thickness 0.15)) (justify left bottom) hide)
    )
    (property "Author" "Antmicro" (at 180.975 189.23 0)
      (effects (font (size 1.27 1.27) (thickness 0.15)) (justify left bottom) hide)
    )
    (property "Voltage" "" (at 178.435 189.23 0)
      (effects (font (size 1.27 1.27)) (justify left bottom) hide)
    )
    (property "Dielectric" "" (at 175.895 189.23 0)
      (effects (font (size 1.27 1.27)) (justify left bottom) hide)
    )
    (pin "1")
    (pin "2")
    (instances
      (project "kria-k26-devboard"
        (path ""
          (reference "C36") (unit 1)
        )
      )
    )
  )

  (symbol (lib_id "kria-k26-devboard:GND") (at 220.345 173.99 0) (unit 1)
    (in_bom yes) (on_board yes) (dnp no) (fields_autoplaced)
    (property "Reference" "#PWR066" (at 220.345 180.34 0)
      (effects (font (size 1.27 1.27)) hide)
    )
    (property "Value" "GND" (at 220.345 179.07 0)
      (effects (font (size 1.27 1.27)))
    )
    (property "Footprint" "" (at 229.235 181.61 0)
      (effects (font (size 1.27 1.27) (thickness 0.15)) (justify left bottom) hide)
    )
    (property "Datasheet" "" (at 229.235 186.69 0)
      (effects (font (size 1.27 1.27) (thickness 0.15)) (justify left bottom) hide)
    )
    (property "Author" "Antmicro" (at 229.235 181.61 0)
      (effects (font (size 1.27 1.27) (thickness 0.15)) (justify left bottom) hide)
    )
    (property "License" "Apache-2.0" (at 229.235 184.15 0)
      (effects (font (size 1.27 1.27) (thickness 0.15)) (justify left bottom) hide)
    )
    (pin "1")
    (instances
      (project "kria-k26-devboard"
        (path ""
          (reference "#PWR066") (unit 1)
        )
      )
    )
  )

  (symbol (lib_id "kria-k26-devboard:GND") (at 168.91 199.39 0) (unit 1)
    (in_bom yes) (on_board yes) (dnp no)
    (property "Reference" "#PWR064" (at 168.91 205.74 0)
      (effects (font (size 1.27 1.27)) hide)
    )
    (property "Value" "GND" (at 168.91 203.2 0)
      (effects (font (size 1.27 1.27)))
    )
    (property "Footprint" "" (at 177.8 207.01 0)
      (effects (font (size 1.27 1.27) (thickness 0.15)) (justify left bottom) hide)
    )
    (property "Datasheet" "" (at 177.8 212.09 0)
      (effects (font (size 1.27 1.27) (thickness 0.15)) (justify left bottom) hide)
    )
    (property "Author" "Antmicro" (at 177.8 207.01 0)
      (effects (font (size 1.27 1.27) (thickness 0.15)) (justify left bottom) hide)
    )
    (property "License" "Apache-2.0" (at 177.8 209.55 0)
      (effects (font (size 1.27 1.27) (thickness 0.15)) (justify left bottom) hide)
    )
    (pin "1")
    (instances
      (project "kria-k26-devboard"
        (path ""
          (reference "#PWR064") (unit 1)
        )
      )
    )
  )

  (symbol (lib_id "kria-k26-devboard:GND") (at 245.11 199.39 0) (mirror y) (unit 1)
    (in_bom yes) (on_board yes) (dnp no)
    (property "Reference" "#PWR068" (at 245.11 205.74 0)
      (effects (font (size 1.27 1.27)) hide)
    )
    (property "Value" "GND" (at 245.11 203.2 0)
      (effects (font (size 1.27 1.27)))
    )
    (property "Footprint" "" (at 236.22 207.01 0)
      (effects (font (size 1.27 1.27) (thickness 0.15)) (justify left bottom) hide)
    )
    (property "Datasheet" "" (at 236.22 212.09 0)
      (effects (font (size 1.27 1.27) (thickness 0.15)) (justify left bottom) hide)
    )
    (property "Author" "Antmicro" (at 236.22 207.01 0)
      (effects (font (size 1.27 1.27) (thickness 0.15)) (justify left bottom) hide)
    )
    (property "License" "Apache-2.0" (at 236.22 209.55 0)
      (effects (font (size 1.27 1.27) (thickness 0.15)) (justify left bottom) hide)
    )
    (pin "1")
    (instances
      (project "kria-k26-devboard"
        (path ""
          (reference "#PWR068") (unit 1)
        )
      )
    )
  )

  (symbol (lib_id "kria-k26-devboard:PTVS5V0Z1USKP") (at 200.025 173.99 90) (unit 1)
    (in_bom yes) (on_board yes) (dnp no) (fields_autoplaced)
    (property "Reference" "D2" (at 196.215 168.5925 90)
      (effects (font (size 1.524 1.524)) (justify left))
    )
    (property "Value" "PTVS5V0Z1USKP" (at 205.105 152.4 0)
      (effects (font (size 1.27 1.27) (thickness 0.15)) (justify left bottom) hide)
    )
    (property "Footprint" "kria-k26-devboard-footprints:SOD-964" (at 207.645 152.4 0)
      (effects (font (size 1.27 1.27) (thickness 0.15)) (justify left bottom) hide)
    )
    (property "Datasheet" "https://pl.mouser.com/datasheet/2/916/PTVS5V0Z1USKP-1600477.pdf" (at 210.185 152.4 0)
      (effects (font (size 1.27 1.27) (thickness 0.15)) (justify left bottom) hide)
    )
    (property "Manufacturer" "Nexperia" (at 212.725 152.4 0)
      (effects (font (size 1.27 1.27) (thickness 0.15)) (justify left bottom) hide)
    )
    (property "MPN" "PTVS5V0Z1USKPYL" (at 196.215 171.7674 90)
      (effects (font (size 1.27 1.27) (thickness 0.15)) (justify left))
    )
    (property "Author" "Antmicro" (at 217.805 152.4 0)
      (effects (font (size 1.27 1.27) (thickness 0.15)) (justify left bottom) hide)
    )
    (property "License" "Apache-2.0" (at 220.345 152.4 0)
      (effects (font (size 1.27 1.27) (thickness 0.15)) (justify left bottom) hide)
    )
    (pin "A")
    (pin "K")
    (instances
      (project "kria-k26-devboard"
        (path ""
          (reference "D2") (unit 1)
        )
      )
    )
  )

  (symbol (lib_id "kria-k26-devboard:TPD4E05U06QDQARQ1") (at 247.65 187.96 0) (unit 1)
    (in_bom yes) (on_board yes) (dnp no)
    (property "Reference" "U15" (at 251.46 183.515 0)
      (effects (font (size 1.27 1.27) (thickness 0.15)) (justify left))
    )
    (property "Value" "TPD4E05U06QDQARQ1" (at 248.92 201.295 0)
      (effects (font (size 1.27 1.27) (thickness 0.15)) (justify left))
    )
    (property "Footprint" "kria-k26-devboard-footprints:USON-10_2.5x1mm_P0.5mm" (at 271.78 193.04 0)
      (effects (font (size 1.27 1.27) (thickness 0.15)) (justify left bottom) hide)
    )
    (property "Datasheet" "https://www.ti.com/lit/ds/symlink/tpd4e05u06-q1.pdf?HQS=dis-mous-null-mousermode-dsf-pf-null-wwe&ts=1663591265741&ref_url=https%253A%252F%252Fwww.mouser.com%252F" (at 271.78 195.58 0)
      (effects (font (size 1.27 1.27) (thickness 0.15)) (justify left bottom) hide)
    )
    (property "Manufacturer" "Texas Instruments" (at 271.78 198.12 0)
      (effects (font (size 1.27 1.27) (thickness 0.15)) (justify left bottom) hide)
    )
    (property "MPN" "TPD4E05U06QDQARQ1" (at 271.78 200.66 0)
      (effects (font (size 1.27 1.27) (thickness 0.15)) (justify left bottom) hide)
    )
    (property "Author" "Antmicro" (at 271.78 203.2 0)
      (effects (font (size 1.27 1.27) (thickness 0.15)) (justify left bottom) hide)
    )
    (property "License" "Apache-2.0" (at 271.78 205.74 0)
      (effects (font (size 1.27 1.27) (thickness 0.15)) (justify left bottom) hide)
    )
    (pin "1")
    (pin "10")
    (pin "2")
    (pin "3")
    (pin "4")
    (pin "5")
    (pin "6")
    (pin "7")
    (pin "8")
    (pin "9")
    (instances
      (project "kria-k26-devboard"
        (path ""
          (reference "U15") (unit 1)
        )
      )
    )
  )

  (symbol (lib_id "kria-k26-devboard:GND") (at 206.375 173.99 0) (unit 1)
    (in_bom yes) (on_board yes) (dnp no) (fields_autoplaced)
    (property "Reference" "#PWR0368" (at 206.375 180.34 0)
      (effects (font (size 1.27 1.27)) hide)
    )
    (property "Value" "GND" (at 206.375 179.07 0)
      (effects (font (size 1.27 1.27)))
    )
    (property "Footprint" "" (at 215.265 181.61 0)
      (effects (font (size 1.27 1.27) (thickness 0.15)) (justify left bottom) hide)
    )
    (property "Datasheet" "" (at 215.265 186.69 0)
      (effects (font (size 1.27 1.27) (thickness 0.15)) (justify left bottom) hide)
    )
    (property "Author" "Antmicro" (at 215.265 181.61 0)
      (effects (font (size 1.27 1.27) (thickness 0.15)) (justify left bottom) hide)
    )
    (property "License" "Apache-2.0" (at 215.265 184.15 0)
      (effects (font (size 1.27 1.27) (thickness 0.15)) (justify left bottom) hide)
    )
    (pin "1")
    (instances
      (project "kria-k26-devboard"
        (path ""
          (reference "#PWR0368") (unit 1)
        )
      )
    )
  )

  (symbol (lib_id "kria-k26-devboard:TPD4E05U06QDQARQ1") (at 170.18 187.96 0) (unit 1)
    (in_bom yes) (on_board yes) (dnp no)
    (property "Reference" "U14" (at 173.99 183.515 0)
      (effects (font (size 1.27 1.27) (thickness 0.15)) (justify left))
    )
    (property "Value" "TPD4E05U06QDQARQ1" (at 171.45 201.295 0)
      (effects (font (size 1.27 1.27) (thickness 0.15)) (justify left))
    )
    (property "Footprint" "kria-k26-devboard-footprints:USON-10_2.5x1mm_P0.5mm" (at 194.31 193.04 0)
      (effects (font (size 1.27 1.27) (thickness 0.15)) (justify left bottom) hide)
    )
    (property "Datasheet" "https://www.ti.com/lit/ds/symlink/tpd4e05u06-q1.pdf?HQS=dis-mous-null-mousermode-dsf-pf-null-wwe&ts=1663591265741&ref_url=https%253A%252F%252Fwww.mouser.com%252F" (at 194.31 195.58 0)
      (effects (font (size 1.27 1.27) (thickness 0.15)) (justify left bottom) hide)
    )
    (property "Manufacturer" "Texas Instruments" (at 194.31 198.12 0)
      (effects (font (size 1.27 1.27) (thickness 0.15)) (justify left bottom) hide)
    )
    (property "MPN" "TPD4E05U06QDQARQ1" (at 194.31 200.66 0)
      (effects (font (size 1.27 1.27) (thickness 0.15)) (justify left bottom) hide)
    )
    (property "Author" "Antmicro" (at 194.31 203.2 0)
      (effects (font (size 1.27 1.27) (thickness 0.15)) (justify left bottom) hide)
    )
    (property "License" "Apache-2.0" (at 194.31 205.74 0)
      (effects (font (size 1.27 1.27) (thickness 0.15)) (justify left bottom) hide)
    )
    (pin "1")
    (pin "10")
    (pin "2")
    (pin "3")
    (pin "4")
    (pin "5")
    (pin "6")
    (pin "7")
    (pin "8")
    (pin "9")
    (instances
      (project "kria-k26-devboard"
        (path ""
          (reference "U14") (unit 1)
        )
      )
    )
  )

  (symbol (lib_id "kria-k26-devboard:GND") (at 200.025 173.99 0) (unit 1)
    (in_bom yes) (on_board yes) (dnp no) (fields_autoplaced)
    (property "Reference" "#PWR0378" (at 200.025 180.34 0)
      (effects (font (size 1.27 1.27)) hide)
    )
    (property "Value" "GND" (at 200.025 179.07 0)
      (effects (font (size 1.27 1.27)))
    )
    (property "Footprint" "" (at 208.915 181.61 0)
      (effects (font (size 1.27 1.27) (thickness 0.15)) (justify left bottom) hide)
    )
    (property "Datasheet" "" (at 208.915 186.69 0)
      (effects (font (size 1.27 1.27) (thickness 0.15)) (justify left bottom) hide)
    )
    (property "Author" "Antmicro" (at 208.915 181.61 0)
      (effects (font (size 1.27 1.27) (thickness 0.15)) (justify left bottom) hide)
    )
    (property "License" "Apache-2.0" (at 208.915 184.15 0)
      (effects (font (size 1.27 1.27) (thickness 0.15)) (justify left bottom) hide)
    )
    (pin "1")
    (instances
      (project "kria-k26-devboard"
        (path ""
          (reference "#PWR0378") (unit 1)
        )
      )
    )
  )

  (symbol (lib_id "kria-k26-devboard:GND") (at 213.36 173.99 0) (unit 1)
    (in_bom yes) (on_board yes) (dnp no) (fields_autoplaced)
    (property "Reference" "#PWR0371" (at 213.36 180.34 0)
      (effects (font (size 1.27 1.27)) hide)
    )
    (property "Value" "GND" (at 213.36 179.07 0)
      (effects (font (size 1.27 1.27)))
    )
    (property "Footprint" "" (at 222.25 181.61 0)
      (effects (font (size 1.27 1.27) (thickness 0.15)) (justify left bottom) hide)
    )
    (property "Datasheet" "" (at 222.25 186.69 0)
      (effects (font (size 1.27 1.27) (thickness 0.15)) (justify left bottom) hide)
    )
    (property "Author" "Antmicro" (at 222.25 181.61 0)
      (effects (font (size 1.27 1.27) (thickness 0.15)) (justify left bottom) hide)
    )
    (property "License" "Apache-2.0" (at 222.25 184.15 0)
      (effects (font (size 1.27 1.27) (thickness 0.15)) (justify left bottom) hide)
    )
    (pin "1")
    (instances
      (project "kria-k26-devboard"
        (path ""
          (reference "#PWR0371") (unit 1)
        )
      )
    )
  )
)
